# SCM (Grand Teton) — schematic netlist excerpt (pin names and nets, part order shuffled) for the footprints in the layout excerpt that follows; sources: Cadence DE-HDL packaged netlist, KiCad conversion of 12092022_DA0F0TMDCD0_F0T_Management_Board_D_brd_V3_OCP.brd

R808  Q_RES  10K 1% CHIP  pkg 0402LF  page 34 : A = PU_FPGA_CONFIG_DONE ; B = PVCCIO_AUX_PLD
C115  Q_CAP  1UF 25V 10% X6S  pkg C0402  page 16 : A = P3V3_AUX ; B = GND

(kicad_pcb
	(version 20260206)
	(generator "pcbnew")
	(generator_version "10.0")
	(general
		(thickness 1.6)
		(legacy_teardrops no)
	)
	(paper "A4")
	(title_block
		(title "12092022_DA0F0TMDCD0_F0T_Management_Board_D_brd_V3_OCP.brd")
		(comment 1 "Grand Teton / footprints 809-810 of 1440")
	)
	(layers
		(0 "F.Cu" signal "TOP")
		(4 "In1.Cu" signal "GND")
		(6 "In2.Cu" signal "IN1")
		(8 "In3.Cu" signal "GND1")
		(10 "In4.Cu" signal "IN2")
		(12 "In5.Cu" signal "VCC")
		(14 "In6.Cu" signal "VCC1")
		(16 "In7.Cu" signal "IN3")
		(18 "In8.Cu" signal "GND2")
		(20 "In9.Cu" signal "IN4")
		(22 "In10.Cu" signal "GND3")
		(2 "B.Cu" signal "BOTTOM")
		(9 "F.Adhes" user "F.Adhesive")
		(11 "B.Adhes" user "B.Adhesive")
		(13 "F.Paste" user "Package Geometry/Pastemask Top")
		(15 "B.Paste" user "Package Geometry/Pastemask Bottom")
		(5 "F.SilkS" user "Ref Des/Silkscreen Top")
		(7 "B.SilkS" user "Ref Des/Silkscreen Bottom")
		(1 "F.Mask" user "Board Geometry/Soldermask Top")
		(3 "B.Mask" user "Board Geometry/Soldermask Bottom")
		(17 "Dwgs.User" user "User.Drawings")
		(19 "Cmts.User" user "User.Comments")
		(21 "Eco1.User" user "User.Eco1")
		(23 "Eco2.User" user "User.Eco2")
		(25 "Edge.Cuts" user "Board Geometry/Outline")
		(27 "Margin" user)
		(31 "F.CrtYd" user "Package Geometry/Place Bound Top")
		(29 "B.CrtYd" user "Package Geometry/Place Bound Bottom")
		(35 "F.Fab" user "Ref Des/Assembly Top")
		(33 "B.Fab" user "Ref Des/Assembly Bottom")
	)
	(footprint ""
		(layer "B.Cu")
		(at 14.2494 -83.693 90)
		(property "Reference" "R808"
			(at 0 0 90)
			(layer "B.SilkS")
			(hide yes)
			(effects
				(font
					(size 1.27 1.27)
				)
				(justify mirror)
			)
		)
		(property "Value" ""
			(at 0 0 90)
			(layer "B.Fab")
			(effects
				(font
					(size 1.27 1.27)
				)
				(justify mirror)
			)
		)
		(duplicate_pad_numbers_are_jumpers no)
		(fp_line
			(start 0.7874 -0.4064)
			(end -0.7874 -0.4064)
			(stroke
				(width 0.1524)
				(type default)
			)
			(layer "B.SilkS")
		)
		(fp_line
			(start -0.7874 -0.4064)
			(end -0.7874 0.4064)
			(stroke
				(width 0.1524)
				(type default)
			)
			(layer "B.SilkS")
		)
		(fp_line
			(start 0.7874 0.4064)
			(end 0.7874 -0.4064)
			(stroke
				(width 0.1524)
				(type default)
			)
			(layer "B.SilkS")
		)
		(fp_line
			(start -0.7874 0.4064)
			(end 0.7874 0.4064)
			(stroke
				(width 0.1524)
				(type default)
			)
			(layer "B.SilkS")
		)
		(fp_line
			(start 0.67945 -0.305054)
			(end 0.12065 -0.305054)
			(stroke
				(width 0.1)
				(type default)
			)
			(layer "B.Fab")
		)
		(fp_line
			(start 0.12065 -0.305054)
			(end 0.12065 -0.2794)
			(stroke
				(width 0.1)
				(type default)
			)
			(layer "B.Fab")
		)
		(fp_line
			(start -0.12065 -0.3048)
			(end -0.67945 -0.3048)
			(stroke
				(width 0.1)
				(type default)
			)
			(layer "B.Fab")
		)
		(fp_line
			(start -0.67945 -0.3048)
			(end -0.67945 0.3048)
			(stroke
				(width 0.1)
				(type default)
			)
			(layer "B.Fab")
		)
		(fp_line
			(start 0.12065 -0.2794)
			(end -0.12065 -0.2794)
			(stroke
				(width 0.1)
				(type default)
			)
			(layer "B.Fab")
		)
		(fp_line
			(start -0.12065 -0.2794)
			(end -0.12065 -0.3048)
			(stroke
				(width 0.1)
				(type default)
			)
			(layer "B.Fab")
		)
		(fp_line
			(start 0.12065 0.2794)
			(end 0.12065 0.3048)
			(stroke
				(width 0.1)
				(type default)
			)
			(layer "B.Fab")
		)
		(fp_line
			(start -0.120396 0.2794)
			(end 0.12065 0.2794)
			(stroke
				(width 0.1)
				(type default)
			)
			(layer "B.Fab")
		)
		(fp_line
			(start 0.67945 0.3048)
			(end 0.67945 -0.305054)
			(stroke
				(width 0.1)
				(type default)
			)
			(layer "B.Fab")
		)
		(fp_line
			(start 0.12065 0.3048)
			(end 0.67945 0.3048)
			(stroke
				(width 0.1)
				(type default)
			)
			(layer "B.Fab")
		)
		(fp_line
			(start -0.120396 0.3048)
			(end -0.120396 0.2794)
			(stroke
				(width 0.1)
				(type default)
			)
			(layer "B.Fab")
		)
		(fp_line
			(start -0.67945 0.3048)
			(end -0.120396 0.3048)
			(stroke
				(width 0.1)
				(type default)
			)
			(layer "B.Fab")
		)
		(pad "1" smd circle
			(at 0.40005 0 270)
			(size 0 0)
			(layers "B.Cu" "B.Mask" "B.Paste")
			(net "PU_FPGA_CONFIG_DONE")
		)
		(pad "2" smd circle
			(at -0.40005 0 270)
			(size 0 0)
			(layers "B.Cu" "B.Mask" "B.Paste")
			(net "PVCCIO_AUX_PLD")
		)
	)
	(footprint ""
		(layer "B.Cu")
		(at 50.240692 -55.170832)
		(property "Reference" "C115"
			(at 0 0 0)
			(layer "B.SilkS")
			(hide yes)
			(effects
				(font
					(size 1.27 1.27)
				)
				(justify mirror)
			)
		)
		(property "Value" ""
			(at 0 0 0)
			(layer "B.Fab")
			(effects
				(font
					(size 1.27 1.27)
				)
				(justify mirror)
			)
		)
		(duplicate_pad_numbers_are_jumpers no)
		(fp_line
			(start -0.7874 -0.4064)
			(end -0.7874 0.4064)
			(stroke
				(width 0.1524)
				(type default)
			)
			(layer "B.SilkS")
		)
		(fp_line
			(start -0.7874 0.4064)
			(end 0.7874 0.4064)
			(stroke
				(width 0.1524)
				(type default)
			)
			(layer "B.SilkS")
		)
		(fp_line
			(start 0.7874 -0.4064)
			(end -0.7874 -0.4064)
			(stroke
				(width 0.1524)
				(type default)
			)
			(layer "B.SilkS")
		)
		(fp_line
			(start 0.7874 0.4064)
			(end 0.7874 -0.4064)
			(stroke
				(width 0.1524)
				(type default)
			)
			(layer "B.SilkS")
		)
		(fp_line
			(start -0.67945 -0.3048)
			(end -0.67945 0.3048)
			(stroke
				(width 0.1)
				(type default)
			)
			(layer "B.Fab")
		)
		(fp_line
			(start -0.67945 0.3048)
			(end -0.120396 0.3048)
			(stroke
				(width 0.1)
				(type default)
			)
			(layer "B.Fab")
		)
		(fp_line
			(start -0.12065 -0.3048)
			(end -0.67945 -0.3048)
			(stroke
				(width 0.1)
				(type default)
			)
			(layer "B.Fab")
		)
		(fp_line
			(start -0.12065 -0.2794)
			(end -0.12065 -0.3048)
			(stroke
				(width 0.1)
				(type default)
			)
			(layer "B.Fab")
		)
		(fp_line
			(start -0.120396 0.2794)
			(end 0.12065 0.2794)
			(stroke
				(width 0.1)
				(type default)
			)
			(layer "B.Fab")
		)
		(fp_line
			(start -0.120396 0.3048)
			(end -0.120396 0.2794)
			(stroke
				(width 0.1)
				(type default)
			)
			(layer "B.Fab")
		)
		(fp_line
			(start 0.12065 -0.305054)
			(end 0.12065 -0.2794)
			(stroke
				(width 0.1)
				(type default)
			)
			(layer "B.Fab")
		)
		(fp_line
			(start 0.12065 -0.2794)
			(end -0.12065 -0.2794)
			(stroke
				(width 0.1)
				(type default)
			)
			(layer "B.Fab")
		)
		(fp_line
			(start 0.12065 0.2794)
			(end 0.12065 0.3048)
			(stroke
				(width 0.1)
				(type default)
			)
			(layer "B.Fab")
		)
		(fp_line
			(start 0.12065 0.3048)
			(end 0.67945 0.3048)
			(stroke
				(width 0.1)
				(type default)
			)
			(layer "B.Fab")
		)
		(fp_line
			(start 0.67945 -0.305054)
			(end 0.12065 -0.305054)
			(stroke
				(width 0.1)
				(type default)
			)
			(layer "B.Fab")
		)
		(fp_line
			(start 0.67945 0.3048)
			(end 0.67945 -0.305054)
			(stroke
				(width 0.1)
				(type default)
			)
			(layer "B.Fab")
		)
		(pad "1" smd circle
			(at 0.40005 0 180)
			(size 0 0)
			(layers "B.Cu" "B.Mask" "B.Paste")
			(net "P3V3_AUX")
		)
		(pad "2" smd circle
			(at -0.40005 0 180)
			(size 0 0)
			(layers "B.Cu" "B.Mask" "B.Paste")
			(net "GND")
		)
	)
)
